(kicad_pcb
	(version 20260206)
	(generator "pcbnew")
	(generator_version "10.0")
	(general
		(thickness 1.6)
		(legacy_teardrops no)
	)
	(paper "A4")
	(title_block
		(title "01162023_DA0F0TEBIF0_F0T_Expander_BD_F_brd_V02_OCP.brd")
		(comment 1 "Grand Teton / footprints 5930-5937 of 9728")
	)
	(layers
		(0 "F.Cu" signal "TOP")
		(4 "In1.Cu" signal "GND")
		(6 "In2.Cu" signal "VCC")
		(8 "In3.Cu" signal "VCC1")
		(10 "In4.Cu" signal "GND1")
		(12 "In5.Cu" signal "IN1")
		(14 "In6.Cu" signal "GND2")
		(16 "In7.Cu" signal "IN2")
		(18 "In8.Cu" signal "GND3")
		(20 "In9.Cu" signal "IN3")
		(22 "In10.Cu" signal "GND4")
		(24 "In11.Cu" signal "IN4")
		(26 "In12.Cu" signal "GND5")
		(28 "In13.Cu" signal "IN5")
		(30 "In14.Cu" signal "GND6")
		(32 "In15.Cu" signal "IN6")
		(34 "In16.Cu" signal "GND7")
		(2 "B.Cu" signal "BOTTOM")
		(9 "F.Adhes" user "F.Adhesive")
		(11 "B.Adhes" user "B.Adhesive")
		(13 "F.Paste" user "Package Geometry/Pastemask Top")
		(15 "B.Paste" user "Package Geometry/Pastemask Bottom")
		(5 "F.SilkS" user "Ref Des/Silkscreen Top")
		(7 "B.SilkS" user "Ref Des/Silkscreen Bottom")
		(1 "F.Mask" user "Board Geometry/Soldermask Top")
		(3 "B.Mask" user "Board Geometry/Soldermask Bottom")
		(17 "Dwgs.User" user "User.Drawings")
		(19 "Cmts.User" user "User.Comments")
		(21 "Eco1.User" user "User.Eco1")
		(23 "Eco2.User" user "User.Eco2")
		(25 "Edge.Cuts" user "Board Geometry/Outline")
		(27 "Margin" user)
		(31 "F.CrtYd" user "Package Geometry/Place Bound Top")
		(29 "B.CrtYd" user "Package Geometry/Place Bound Bottom")
		(35 "F.Fab" user "Ref Des/Assembly Top")
		(33 "B.Fab" user "Ref Des/Assembly Bottom")
	)
	(footprint ""
		(layer "F.Cu")
		(at 319.609724 -350.098614 90)
		(property "Reference" "C544"
			(at 0 0 90)
			(layer "F.SilkS")
			(hide yes)
			(effects
				(font
					(size 1.27 1.27)
				)
			)
		)
		(property "Value" ""
			(at 0 0 90)
			(layer "F.Fab")
			(effects
				(font
					(size 1.27 1.27)
				)
			)
		)
		(duplicate_pad_numbers_are_jumpers no)
		(fp_line
			(start 0.299974 -0.150114)
			(end 0.299974 0.150114)
			(stroke
				(width 0.1)
				(type default)
			)
			(layer "F.Fab")
		)
		(fp_line
			(start -0.299974 -0.150114)
			(end 0.299974 -0.150114)
			(stroke
				(width 0.1)
				(type default)
			)
			(layer "F.Fab")
		)
		(fp_line
			(start 0.299974 0.150114)
			(end -0.299974 0.150114)
			(stroke
				(width 0.1)
				(type default)
			)
			(layer "F.Fab")
		)
		(fp_line
			(start -0.299974 0.150114)
			(end -0.299974 -0.150114)
			(stroke
				(width 0.1)
				(type default)
			)
			(layer "F.Fab")
		)
		(pad "1" smd rect
			(at -0.2667 0 90)
			(size 0.3048 0.381)
			(layers "F.Cu" "F.Mask" "F.Paste")
			(net "P5E_PEX2_STN5_TX_DN<83>")
		)
		(pad "2" smd rect
			(at 0.2667 0 90)
			(size 0.3048 0.381)
			(layers "F.Cu" "F.Mask" "F.Paste")
			(net "P5E_PEX2_STN5_TX_C_DN<83>")
		)
	)
	(footprint ""
		(layer "F.Cu")
		(at 352.39452 -303.649634 90)
		(property "Reference" "PC183"
			(at 0 0 90)
			(layer "F.SilkS")
			(hide yes)
			(effects
				(font
					(size 1.27 1.27)
				)
			)
		)
		(property "Value" ""
			(at 0 0 90)
			(layer "F.Fab")
			(effects
				(font
					(size 1.27 1.27)
				)
			)
		)
		(duplicate_pad_numbers_are_jumpers no)
		(fp_line
			(start 1.524 -0.762)
			(end 1.524 0.762)
			(stroke
				(width 0.1524)
				(type default)
			)
			(layer "F.SilkS")
		)
		(fp_line
			(start -1.524 -0.762)
			(end 1.524 -0.762)
			(stroke
				(width 0.1524)
				(type default)
			)
			(layer "F.SilkS")
		)
		(fp_line
			(start 1.524 0.762)
			(end -1.524 0.762)
			(stroke
				(width 0.1524)
				(type default)
			)
			(layer "F.SilkS")
		)
		(fp_line
			(start -1.524 0.762)
			(end -1.524 -0.762)
			(stroke
				(width 0.1524)
				(type default)
			)
			(layer "F.SilkS")
		)
		(fp_line
			(start 1.1049 -0.724916)
			(end -1.1049 -0.724916)
			(stroke
				(width 0.1)
				(type default)
			)
			(layer "F.Fab")
		)
		(fp_line
			(start -1.1049 -0.724916)
			(end -1.1049 0.724916)
			(stroke
				(width 0.1)
				(type default)
			)
			(layer "F.Fab")
		)
		(fp_line
			(start 1.1049 0.724916)
			(end 1.1049 -0.724916)
			(stroke
				(width 0.1)
				(type default)
			)
			(layer "F.Fab")
		)
		(fp_line
			(start -1.1049 0.724916)
			(end 1.1049 0.724916)
			(stroke
				(width 0.1)
				(type default)
			)
			(layer "F.Fab")
		)
		(pad "1" smd rect
			(at -0.889 0 270)
			(size 1.016 1.27)
			(layers "F.Cu" "F.Mask" "F.Paste")
			(net "P0V8_PEX3")
		)
		(pad "2" smd rect
			(at 0.889 0 270)
			(size 1.016 1.27)
			(layers "F.Cu" "F.Mask" "F.Paste")
			(net "GND")
		)
	)
	(footprint ""
		(layer "F.Cu")
		(at 267.569442 -256.888234 -90)
		(property "Reference" "R4583"
			(at 0 0 270)
			(layer "F.SilkS")
			(hide yes)
			(effects
				(font
					(size 1.27 1.27)
				)
			)
		)
		(property "Value" ""
			(at 0 0 270)
			(layer "F.Fab")
			(effects
				(font
					(size 1.27 1.27)
				)
			)
		)
		(duplicate_pad_numbers_are_jumpers no)
		(fp_line
			(start -0.7874 0.4064)
			(end -0.7874 -0.4064)
			(stroke
				(width 0.1524)
				(type default)
			)
			(layer "F.SilkS")
		)
		(fp_line
			(start 0.7874 0.4064)
			(end -0.7874 0.4064)
			(stroke
				(width 0.1524)
				(type default)
			)
			(layer "F.SilkS")
		)
		(fp_line
			(start -0.7874 -0.4064)
			(end 0.7874 -0.4064)
			(stroke
				(width 0.1524)
				(type default)
			)
			(layer "F.SilkS")
		)
		(fp_line
			(start 0.7874 -0.4064)
			(end 0.7874 0.4064)
			(stroke
				(width 0.1524)
				(type default)
			)
			(layer "F.SilkS")
		)
		(fp_line
			(start -0.67945 0.3048)
			(end -0.67945 -0.305054)
			(stroke
				(width 0.1)
				(type default)
			)
			(layer "F.Fab")
		)
		(fp_line
			(start -0.12065 0.3048)
			(end -0.67945 0.3048)
			(stroke
				(width 0.1)
				(type default)
			)
			(layer "F.Fab")
		)
		(fp_line
			(start 0.120396 0.3048)
			(end 0.120396 0.2794)
			(stroke
				(width 0.1)
				(type default)
			)
			(layer "F.Fab")
		)
		(fp_line
			(start 0.67945 0.3048)
			(end 0.120396 0.3048)
			(stroke
				(width 0.1)
				(type default)
			)
			(layer "F.Fab")
		)
		(fp_line
			(start -0.12065 0.2794)
			(end -0.12065 0.3048)
			(stroke
				(width 0.1)
				(type default)
			)
			(layer "F.Fab")
		)
		(fp_line
			(start 0.120396 0.2794)
			(end -0.12065 0.2794)
			(stroke
				(width 0.1)
				(type default)
			)
			(layer "F.Fab")
		)
		(fp_line
			(start -0.12065 -0.2794)
			(end 0.12065 -0.2794)
			(stroke
				(width 0.1)
				(type default)
			)
			(layer "F.Fab")
		)
		(fp_line
			(start 0.12065 -0.2794)
			(end 0.12065 -0.3048)
			(stroke
				(width 0.1)
				(type default)
			)
			(layer "F.Fab")
		)
		(fp_line
			(start 0.12065 -0.3048)
			(end 0.67945 -0.3048)
			(stroke
				(width 0.1)
				(type default)
			)
			(layer "F.Fab")
		)
		(fp_line
			(start 0.67945 -0.3048)
			(end 0.67945 0.3048)
			(stroke
				(width 0.1)
				(type default)
			)
			(layer "F.Fab")
		)
		(fp_line
			(start -0.67945 -0.305054)
			(end -0.12065 -0.305054)
			(stroke
				(width 0.1)
				(type default)
			)
			(layer "F.Fab")
		)
		(fp_line
			(start -0.12065 -0.305054)
			(end -0.12065 -0.2794)
			(stroke
				(width 0.1)
				(type default)
			)
			(layer "F.Fab")
		)
		(pad "1" smd circle
			(at -0.40005 0 270)
			(size 0 0)
			(layers "F.Cu" "F.Mask" "F.Paste")
			(net "PCEPLL5_VDDA18_PEX2")
		)
		(pad "2" smd circle
			(at 0.40005 0 270)
			(size 0 0)
			(layers "F.Cu" "F.Mask" "F.Paste")
			(net "PCEPLL5_VDDA18_PEX2_R")
		)
	)
	(footprint ""
		(layer "F.Cu")
		(at 376.936 -187.833)
		(property "Reference" "R4652"
			(at 0 0 0)
			(layer "F.SilkS")
			(hide yes)
			(effects
				(font
					(size 1.27 1.27)
				)
			)
		)
		(property "Value" ""
			(at 0 0 0)
			(layer "F.Fab")
			(effects
				(font
					(size 1.27 1.27)
				)
			)
		)
		(duplicate_pad_numbers_are_jumpers no)
		(fp_line
			(start -0.7874 -0.4064)
			(end 0.7874 -0.4064)
			(stroke
				(width 0.1524)
				(type default)
			)
			(layer "F.SilkS")
		)
		(fp_line
			(start -0.7874 0.4064)
			(end -0.7874 -0.4064)
			(stroke
				(width 0.1524)
				(type default)
			)
			(layer "F.SilkS")
		)
		(fp_line
			(start 0.7874 -0.4064)
			(end 0.7874 0.4064)
			(stroke
				(width 0.1524)
				(type default)
			)
			(layer "F.SilkS")
		)
		(fp_line
			(start 0.7874 0.4064)
			(end -0.7874 0.4064)
			(stroke
				(width 0.1524)
				(type default)
			)
			(layer "F.SilkS")
		)
		(fp_line
			(start -0.67945 -0.305054)
			(end -0.12065 -0.305054)
			(stroke
				(width 0.1)
				(type default)
			)
			(layer "F.Fab")
		)
		(fp_line
			(start -0.67945 0.3048)
			(end -0.67945 -0.305054)
			(stroke
				(width 0.1)
				(type default)
			)
			(layer "F.Fab")
		)
		(fp_line
			(start -0.12065 -0.305054)
			(end -0.12065 -0.2794)
			(stroke
				(width 0.1)
				(type default)
			)
			(layer "F.Fab")
		)
		(fp_line
			(start -0.12065 -0.2794)
			(end 0.12065 -0.2794)
			(stroke
				(width 0.1)
				(type default)
			)
			(layer "F.Fab")
		)
		(fp_line
			(start -0.12065 0.2794)
			(end -0.12065 0.3048)
			(stroke
				(width 0.1)
				(type default)
			)
			(layer "F.Fab")
		)
		(fp_line
			(start -0.12065 0.3048)
			(end -0.67945 0.3048)
			(stroke
				(width 0.1)
				(type default)
			)
			(layer "F.Fab")
		)
		(fp_line
			(start 0.120396 0.2794)
			(end -0.12065 0.2794)
			(stroke
				(width 0.1)
				(type default)
			)
			(layer "F.Fab")
		)
		(fp_line
			(start 0.120396 0.3048)
			(end 0.120396 0.2794)
			(stroke
				(width 0.1)
				(type default)
			)
			(layer "F.Fab")
		)
		(fp_line
			(start 0.12065 -0.3048)
			(end 0.67945 -0.3048)
			(stroke
				(width 0.1)
				(type default)
			)
			(layer "F.Fab")
		)
		(fp_line
			(start 0.12065 -0.2794)
			(end 0.12065 -0.3048)
			(stroke
				(width 0.1)
				(type default)
			)
			(layer "F.Fab")
		)
		(fp_line
			(start 0.67945 -0.3048)
			(end 0.67945 0.3048)
			(stroke
				(width 0.1)
				(type default)
			)
			(layer "F.Fab")
		)
		(fp_line
			(start 0.67945 0.3048)
			(end 0.120396 0.3048)
			(stroke
				(width 0.1)
				(type default)
			)
			(layer "F.Fab")
		)
		(pad "1" smd circle
			(at -0.40005 0)
			(size 0 0)
			(layers "F.Cu" "F.Mask" "F.Paste")
			(net "RST_PEX_NIC1_PERST_N")
		)
		(pad "2" smd circle
			(at 0.40005 0)
			(size 0 0)
			(layers "F.Cu" "F.Mask" "F.Paste")
			(net "RST_PEX_NIC1_PERST_R_N")
		)
	)
	(footprint ""
		(layer "F.Cu")
		(at 433.00904 -26.03373)
		(property "Reference" "R4082"
			(at 0 0 0)
			(layer "F.SilkS")
			(hide yes)
			(effects
				(font
					(size 1.27 1.27)
				)
			)
		)
		(property "Value" ""
			(at 0 0 0)
			(layer "F.Fab")
			(effects
				(font
					(size 1.27 1.27)
				)
			)
		)
		(duplicate_pad_numbers_are_jumpers no)
		(fp_line
			(start -0.7874 -0.4064)
			(end 0.7874 -0.4064)
			(stroke
				(width 0.1524)
				(type default)
			)
			(layer "F.SilkS")
		)
		(fp_line
			(start -0.7874 0.4064)
			(end -0.7874 -0.4064)
			(stroke
				(width 0.1524)
				(type default)
			)
			(layer "F.SilkS")
		)
		(fp_line
			(start 0.7874 -0.4064)
			(end 0.7874 0.4064)
			(stroke
				(width 0.1524)
				(type default)
			)
			(layer "F.SilkS")
		)
		(fp_line
			(start 0.7874 0.4064)
			(end -0.7874 0.4064)
			(stroke
				(width 0.1524)
				(type default)
			)
			(layer "F.SilkS")
		)
		(fp_line
			(start -0.67945 -0.305054)
			(end -0.12065 -0.305054)
			(stroke
				(width 0.1)
				(type default)
			)
			(layer "F.Fab")
		)
		(fp_line
			(start -0.67945 0.3048)
			(end -0.67945 -0.305054)
			(stroke
				(width 0.1)
				(type default)
			)
			(layer "F.Fab")
		)
		(fp_line
			(start -0.12065 -0.305054)
			(end -0.12065 -0.2794)
			(stroke
				(width 0.1)
				(type default)
			)
			(layer "F.Fab")
		)
		(fp_line
			(start -0.12065 -0.2794)
			(end 0.12065 -0.2794)
			(stroke
				(width 0.1)
				(type default)
			)
			(layer "F.Fab")
		)
		(fp_line
			(start -0.12065 0.2794)
			(end -0.12065 0.3048)
			(stroke
				(width 0.1)
				(type default)
			)
			(layer "F.Fab")
		)
		(fp_line
			(start -0.12065 0.3048)
			(end -0.67945 0.3048)
			(stroke
				(width 0.1)
				(type default)
			)
			(layer "F.Fab")
		)
		(fp_line
			(start 0.120396 0.2794)
			(end -0.12065 0.2794)
			(stroke
				(width 0.1)
				(type default)
			)
			(layer "F.Fab")
		)
		(fp_line
			(start 0.120396 0.3048)
			(end 0.120396 0.2794)
			(stroke
				(width 0.1)
				(type default)
			)
			(layer "F.Fab")
		)
		(fp_line
			(start 0.12065 -0.3048)
			(end 0.67945 -0.3048)
			(stroke
				(width 0.1)
				(type default)
			)
			(layer "F.Fab")
		)
		(fp_line
			(start 0.12065 -0.2794)
			(end 0.12065 -0.3048)
			(stroke
				(width 0.1)
				(type default)
			)
			(layer "F.Fab")
		)
		(fp_line
			(start 0.67945 -0.3048)
			(end 0.67945 0.3048)
			(stroke
				(width 0.1)
				(type default)
			)
			(layer "F.Fab")
		)
		(fp_line
			(start 0.67945 0.3048)
			(end 0.120396 0.3048)
			(stroke
				(width 0.1)
				(type default)
			)
			(layer "F.Fab")
		)
		(pad "1" smd circle
			(at -0.40005 0)
			(size 0 0)
			(layers "F.Cu" "F.Mask" "F.Paste")
			(net "P3V3_AUX")
		)
		(pad "2" smd circle
			(at 0.40005 0)
			(size 0 0)
			(layers "F.Cu" "F.Mask" "F.Paste")
			(net "PRSNT_SSD15_R_N")
		)
	)
	(footprint ""
		(layer "F.Cu")
		(at 28.406344 -250.070874 -90)
		(property "Reference" "R1126"
			(at 0 0 270)
			(layer "F.SilkS")
			(hide yes)
			(effects
				(font
					(size 1.27 1.27)
				)
			)
		)
		(property "Value" ""
			(at 0 0 270)
			(layer "F.Fab")
			(effects
				(font
					(size 1.27 1.27)
				)
			)
		)
		(duplicate_pad_numbers_are_jumpers no)
		(fp_line
			(start -0.7874 0.4064)
			(end -0.7874 -0.4064)
			(stroke
				(width 0.1524)
				(type default)
			)
			(layer "F.SilkS")
		)
		(fp_line
			(start 0.7874 0.4064)
			(end -0.7874 0.4064)
			(stroke
				(width 0.1524)
				(type default)
			)
			(layer "F.SilkS")
		)
		(fp_line
			(start -0.7874 -0.4064)
			(end 0.7874 -0.4064)
			(stroke
				(width 0.1524)
				(type default)
			)
			(layer "F.SilkS")
		)
		(fp_line
			(start 0.7874 -0.4064)
			(end 0.7874 0.4064)
			(stroke
				(width 0.1524)
				(type default)
			)
			(layer "F.SilkS")
		)
		(fp_line
			(start -0.67945 0.3048)
			(end -0.67945 -0.305054)
			(stroke
				(width 0.1)
				(type default)
			)
			(layer "F.Fab")
		)
		(fp_line
			(start -0.12065 0.3048)
			(end -0.67945 0.3048)
			(stroke
				(width 0.1)
				(type default)
			)
			(layer "F.Fab")
		)
		(fp_line
			(start 0.120396 0.3048)
			(end 0.120396 0.2794)
			(stroke
				(width 0.1)
				(type default)
			)
			(layer "F.Fab")
		)
		(fp_line
			(start 0.67945 0.3048)
			(end 0.120396 0.3048)
			(stroke
				(width 0.1)
				(type default)
			)
			(layer "F.Fab")
		)
		(fp_line
			(start -0.12065 0.2794)
			(end -0.12065 0.3048)
			(stroke
				(width 0.1)
				(type default)
			)
			(layer "F.Fab")
		)
		(fp_line
			(start 0.120396 0.2794)
			(end -0.12065 0.2794)
			(stroke
				(width 0.1)
				(type default)
			)
			(layer "F.Fab")
		)
		(fp_line
			(start -0.12065 -0.2794)
			(end 0.12065 -0.2794)
			(stroke
				(width 0.1)
				(type default)
			)
			(layer "F.Fab")
		)
		(fp_line
			(start 0.12065 -0.2794)
			(end 0.12065 -0.3048)
			(stroke
				(width 0.1)
				(type default)
			)
			(layer "F.Fab")
		)
		(fp_line
			(start 0.12065 -0.3048)
			(end 0.67945 -0.3048)
			(stroke
				(width 0.1)
				(type default)
			)
			(layer "F.Fab")
		)
		(fp_line
			(start 0.67945 -0.3048)
			(end 0.67945 0.3048)
			(stroke
				(width 0.1)
				(type default)
			)
			(layer "F.Fab")
		)
		(fp_line
			(start -0.67945 -0.305054)
			(end -0.12065 -0.305054)
			(stroke
				(width 0.1)
				(type default)
			)
			(layer "F.Fab")
		)
		(fp_line
			(start -0.12065 -0.305054)
			(end -0.12065 -0.2794)
			(stroke
				(width 0.1)
				(type default)
			)
			(layer "F.Fab")
		)
		(pad "1" smd circle
			(at -0.40005 0 270)
			(size 0 0)
			(layers "F.Cu" "F.Mask" "F.Paste")
			(net "PEX0_DBG_MODE3")
		)
		(pad "2" smd circle
			(at 0.40005 0 270)
			(size 0 0)
			(layers "F.Cu" "F.Mask" "F.Paste")
			(net "P1V8_PEX")
		)
	)
	(footprint ""
		(layer "F.Cu")
		(at 121.163588 -343.952322 90)
		(property "Reference" "C364"
			(at 0 0 90)
			(layer "F.SilkS")
			(hide yes)
			(effects
				(font
					(size 1.27 1.27)
				)
			)
		)
		(property "Value" ""
			(at 0 0 90)
			(layer "F.Fab")
			(effects
				(font
					(size 1.27 1.27)
				)
			)
		)
		(duplicate_pad_numbers_are_jumpers no)
		(fp_line
			(start 0.299974 -0.150114)
			(end 0.299974 0.150114)
			(stroke
				(width 0.1)
				(type default)
			)
			(layer "F.Fab")
		)
		(fp_line
			(start -0.299974 -0.150114)
			(end 0.299974 -0.150114)
			(stroke
				(width 0.1)
				(type default)
			)
			(layer "F.Fab")
		)
		(fp_line
			(start 0.299974 0.150114)
			(end -0.299974 0.150114)
			(stroke
				(width 0.1)
				(type default)
			)
			(layer "F.Fab")
		)
		(fp_line
			(start -0.299974 0.150114)
			(end -0.299974 -0.150114)
			(stroke
				(width 0.1)
				(type default)
			)
			(layer "F.Fab")
		)
		(pad "1" smd rect
			(at -0.2667 0 90)
			(size 0.3048 0.381)
			(layers "F.Cu" "F.Mask" "F.Paste")
			(net "P5E_PEX1_STN6_TX_DP<99>")
		)
		(pad "2" smd rect
			(at 0.2667 0 90)
			(size 0.3048 0.381)
			(layers "F.Cu" "F.Mask" "F.Paste")
			(net "P5E_PEX1_STN6_TX_C_DP<99>")
		)
	)
	(footprint ""
		(layer "F.Cu")
		(at 141.441932 -261.026402 180)
		(property "Reference" "C3244"
			(at 0 0 180)
			(layer "F.SilkS")
			(hide yes)
			(effects
				(font
					(size 1.27 1.27)
				)
			)
		)
		(property "Value" ""
			(at 0 0 180)
			(layer "F.Fab")
			(effects
				(font
					(size 1.27 1.27)
				)
			)
		)
		(duplicate_pad_numbers_are_jumpers no)
		(fp_line
			(start 1.2954 0.5842)
			(end -1.2954 0.5842)
			(stroke
				(width 0.1524)
				(type default)
			)
			(layer "F.SilkS")
		)
		(fp_line
			(start 1.2954 -0.5842)
			(end 1.2954 0.5842)
			(stroke
				(width 0.1524)
				(type default)
			)
			(layer "F.SilkS")
		)
		(fp_line
			(start -1.2954 0.5842)
			(end -1.2954 -0.5842)
			(stroke
				(width 0.1524)
				(type default)
			)
			(layer "F.SilkS")
		)
		(fp_line
			(start -1.2954 -0.5842)
			(end 1.2954 -0.5842)
			(stroke
				(width 0.1524)
				(type default)
			)
			(layer "F.SilkS")
		)
		(fp_line
			(start 1.1938 0.4064)
			(end 0.8636 0.4064)
			(stroke
				(width 0.1)
				(type default)
			)
			(layer "F.Fab")
		)
		(fp_line
			(start 1.1938 -0.4064)
			(end 1.1938 0.4064)
			(stroke
				(width 0.1)
				(type default)
			)
			(layer "F.Fab")
		)
		(fp_line
			(start 0.8636 0.4572)
			(end -0.8636 0.4572)
			(stroke
				(width 0.1)
				(type default)
			)
			(layer "F.Fab")
		)
		(fp_line
			(start 0.8636 0.4064)
			(end 0.8636 0.4572)
			(stroke
				(width 0.1)
				(type default)
			)
			(layer "F.Fab")
		)
		(fp_line
			(start 0.8636 -0.4064)
			(end 1.1938 -0.4064)
			(stroke
				(width 0.1)
				(type default)
			)
			(layer "F.Fab")
		)
		(fp_line
			(start 0.8636 -0.4572)
			(end 0.8636 -0.4064)
			(stroke
				(width 0.1)
				(type default)
			)
			(layer "F.Fab")
		)
		(fp_line
			(start -0.8636 0.4572)
			(end -0.8636 0.4064)
			(stroke
				(width 0.1)
				(type default)
			)
			(layer "F.Fab")
		)
		(fp_line
			(start -0.8636 0.4064)
			(end -1.1938 0.4064)
			(stroke
				(width 0.1)
				(type default)
			)
			(layer "F.Fab")
		)
		(fp_line
			(start -0.8636 -0.4064)
			(end -0.8636 -0.4572)
			(stroke
				(width 0.1)
				(type default)
			)
			(layer "F.Fab")
		)
		(fp_line
			(start -0.8636 -0.4572)
			(end 0.8636 -0.4572)
			(stroke
				(width 0.1)
				(type default)
			)
			(layer "F.Fab")
		)
		(fp_line
			(start -1.1938 0.4064)
			(end -1.1938 -0.4064)
			(stroke
				(width 0.1)
				(type default)
			)
			(layer "F.Fab")
		)
		(fp_line
			(start -1.1938 -0.4064)
			(end -0.8636 -0.4064)
			(stroke
				(width 0.1)
				(type default)
			)
			(layer "F.Fab")
		)
		(pad "1" smd rect
			(at -0.7366 0 90)
			(size 0.7112 0.8128)
			(layers "F.Cu" "F.Mask" "F.Paste")
			(net "P1V8_VDDA_PEX1")
		)
		(pad "2" smd rect
			(at 0.7366 0 90)
			(size 0.7112 0.8128)
			(layers "F.Cu" "F.Mask" "F.Paste")
			(net "GND")
		)
	)
)
